(kicad_pcb
	(version 20260206)
	(generator "pcbnew")
	(generator_version "10.0")
	(general
		(thickness 1.6)
		(legacy_teardrops no)
	)
	(paper "A4")
	(title_block
		(title "netronome-mezz — pcbd0082-001_rev01_jul9_a.brd")
		(comment 1 "Open CloudServer (Microsoft) / footprints 111-119 of 714")
	)
	(layers
		(0 "F.Cu" signal "TOP")
		(4 "In1.Cu" signal "02_GND")
		(6 "In2.Cu" signal "03_SIG")
		(8 "In3.Cu" signal "04_SIG")
		(10 "In4.Cu" signal "05_GND")
		(12 "In5.Cu" signal "06_PWR1")
		(14 "In6.Cu" signal "07_SIG")
		(16 "In7.Cu" signal "08_SIG")
		(18 "In8.Cu" signal "09_GND")
		(2 "B.Cu" signal "BOTTOM")
		(9 "F.Adhes" user "F.Adhesive")
		(11 "B.Adhes" user "B.Adhesive")
		(13 "F.Paste" user "Package Geometry/Pastemask Top")
		(15 "B.Paste" user "Package Geometry/Pastemask Bottom")
		(5 "F.SilkS" user "Ref Des/Silkscreen Top")
		(7 "B.SilkS" user "Ref Des/Silkscreen Bottom")
		(1 "F.Mask" user "Board Geometry/Soldermask Top")
		(3 "B.Mask" user "Board Geometry/Soldermask Bottom")
		(17 "Dwgs.User" user "User.Drawings")
		(19 "Cmts.User" user "User.Comments")
		(21 "Eco1.User" user "User.Eco1")
		(23 "Eco2.User" user "User.Eco2")
		(25 "Edge.Cuts" user "Board Geometry/Outline")
		(27 "Margin" user)
		(31 "F.CrtYd" user "Package Geometry/Place Bound Top")
		(29 "B.CrtYd" user "Package Geometry/Place Bound Bottom")
		(35 "F.Fab" user "Ref Des/Assembly Top")
		(33 "B.Fab" user "Ref Des/Assembly Bottom")
		(45 "User.4" user "COMPVAL_TYPE_BOTTOM")
	)
	(footprint ""
		(layer "F.Cu")
		(at 77.051002 6.698996)
		(property "Reference" "V_A-DQ03"
			(at 0 0 0)
			(layer "F.SilkS")
			(hide yes)
			(effects
				(font
					(size 1.27 1.27)
				)
			)
		)
		(property "Value" ""
			(at 0 0 0)
			(layer "F.Fab")
			(effects
				(font
					(size 1.27 1.27)
				)
			)
		)
		(duplicate_pad_numbers_are_jumpers no)
		(pad "1" thru_hole circle
			(at 0 0)
			(size 0.762 0.762)
			(drill 0.20574)
			(layers "*.Cu" "*.Mask")
			(remove_unused_layers no)
			(net "DDR0_32A_DQ3")
			(clearance 0.127)
			(thermal_gap 0.127)
			(padstack
				(mode front_inner_back)
				(layer "Inner"
					(shape circle)
					(size 0.4572 0.4572)
					(clearance 0.1143)
				)
				(layer "B.Cu"
					(shape circle)
					(size 0.4572 0.4572)
					(clearance 0.1143)
				)
			)
		)
	)
	(footprint ""
		(layer "F.Cu")
		(at 38.6715 39.0144 -90)
		(property "Reference" "R402"
			(at 0.25527 -1.397 0)
			(unlocked yes)
			(layer "F.SilkS")
			(effects
				(font
					(size 0.7874 0.5842)
					(thickness 0.127)
				)
				(justify left)
			)
		)
		(property "Value" "680"
			(at -0.148158 1.7526 0)
			(unlocked yes)
			(layer "F.Fab")
			(hide yes)
			(effects
				(font
					(size 1.27 0.9652)
					(thickness 0.000001)
				)
				(justify left)
			)
		)
		(property "Device Type" "REST0283"
			(at -0.148158 1.7526 0)
			(unlocked yes)
			(layer "F.Fab")
			(hide yes)
			(effects
				(font
					(size 1.27 0.9652)
					(thickness 0.000001)
				)
				(justify left)
			)
		)
		(duplicate_pad_numbers_are_jumpers no)
		(fp_circle
			(center 0 0)
			(end 0 -0.127)
			(stroke
				(width 0.2032)
				(type default)
			)
			(fill no)
			(layer "F.SilkS")
		)
		(fp_poly
			(pts
				(xy 0.7874 -1.6637) (xy -0.7874 -1.6637) (xy -0.7874 1.6637) (xy 0.7874 1.6637)
			)
			(stroke
				(width 0)
				(type default)
			)
			(fill no)
			(layer "F.CrtYd")
		)
		(fp_line
			(start -0.4064 0.8128)
			(end -0.4064 -0.8128)
			(stroke
				(width 0.0254)
				(type default)
			)
			(layer "F.Fab")
		)
		(fp_line
			(start 0.4064 0.8128)
			(end -0.4064 0.8128)
			(stroke
				(width 0.0254)
				(type default)
			)
			(layer "F.Fab")
		)
		(fp_line
			(start -0.4064 -0.8128)
			(end 0.4064 -0.8128)
			(stroke
				(width 0.0254)
				(type default)
			)
			(layer "F.Fab")
		)
		(fp_line
			(start 0.4064 -0.8128)
			(end 0.4064 0.8128)
			(stroke
				(width 0.0254)
				(type default)
			)
			(layer "F.Fab")
		)
		(pad "1" smd rect
			(at 0 -0.8001 270)
			(size 0.762 0.9652)
			(layers "F.Cu" "F.Mask" "F.Paste")
			(net "EXT_12.0V")
		)
		(pad "2" smd rect
			(at 0 0.8001 270)
			(size 0.762 0.9652)
			(layers "F.Cu" "F.Mask" "F.Paste")
			(net "10N2370")
		)
		(zone
			(layer "F.Cu")
			(hatch none 0.5)
			(connect_pads
				(clearance 0)
			)
			(min_thickness 0.25)
			(keepout
				(tracks not_allowed)
				(vias allowed)
				(pads allowed)
				(copperpour not_allowed)
				(footprints allowed)
			)
			(placement
				(enabled no)
				(sheetname "")
			)
			(fill
				(thermal_gap 0.5)
				(thermal_bridge_width 0.5)
				(island_removal_mode 0)
			)
			(polygon
				(pts
					(xy 38.9255 38.9509) (xy 38.9255 39.0779) (xy 38.4175 39.0779) (xy 38.4175 38.9509)
				)
			)
		)
	)
	(footprint ""
		(layer "F.Cu")
		(at 73.533 11.938 90)
		(property "Reference" "C265"
			(at -0.254 -1.24333 90)
			(unlocked yes)
			(layer "F.SilkS")
			(effects
				(font
					(size 0.7874 0.5842)
					(thickness 0.127)
				)
				(justify left)
			)
		)
		(property "Value" "1UF"
			(at -0.091846 0.2921 180)
			(unlocked yes)
			(layer "F.Fab")
			(hide yes)
			(effects
				(font
					(size 0.7874 0.5842)
					(thickness 0.2032)
				)
				(justify left)
			)
		)
		(property "Device Type" "CAPC0028"
			(at -0.091846 0.2921 180)
			(unlocked yes)
			(layer "F.Fab")
			(hide yes)
			(effects
				(font
					(size 0.7874 0.5842)
					(thickness 0.2032)
				)
				(justify left)
			)
		)
		(duplicate_pad_numbers_are_jumpers no)
		(fp_poly
			(pts
				(xy 0.635 1.0668) (xy 0.635 -1.0668) (xy -0.635 -1.0668) (xy -0.635 1.0668)
			)
			(stroke
				(width 0)
				(type default)
			)
			(fill no)
			(layer "F.CrtYd")
		)
		(fp_line
			(start 0.254 -0.508)
			(end 0.254 0.508)
			(stroke
				(width 0.0254)
				(type default)
			)
			(layer "F.Fab")
		)
		(fp_line
			(start -0.254 -0.508)
			(end 0.254 -0.508)
			(stroke
				(width 0.0254)
				(type default)
			)
			(layer "F.Fab")
		)
		(fp_line
			(start 0.254 0.508)
			(end -0.254 0.508)
			(stroke
				(width 0.0254)
				(type default)
			)
			(layer "F.Fab")
		)
		(fp_line
			(start -0.254 0.508)
			(end -0.254 -0.508)
			(stroke
				(width 0.0254)
				(type default)
			)
			(layer "F.Fab")
		)
		(pad "1" smd rect
			(at 0 -0.4191 90)
			(size 0.508 0.5334)
			(layers "F.Cu" "F.Mask" "F.Paste")
			(net "DDR_VDDQ")
		)
		(pad "2" smd rect
			(at 0 0.4191 90)
			(size 0.508 0.5334)
			(layers "F.Cu" "F.Mask" "F.Paste")
			(net "GND")
		)
		(zone
			(layer "F.Cu")
			(hatch none 0.5)
			(connect_pads
				(clearance 0)
			)
			(min_thickness 0.25)
			(keepout
				(tracks not_allowed)
				(vias allowed)
				(pads allowed)
				(copperpour not_allowed)
				(footprints allowed)
			)
			(placement
				(enabled no)
				(sheetname "")
			)
			(fill
				(thermal_gap 0.5)
				(thermal_bridge_width 0.5)
				(island_removal_mode 0)
			)
			(polygon
				(pts
					(xy 73.5076 11.9126) (xy 73.5584 11.9126) (xy 73.5584 11.9634) (xy 73.5076 11.9634)
				)
			)
		)
	)
	(footprint ""
		(layer "F.Cu")
		(at 26.543 32.639 180)
		(property "Reference" "R84"
			(at -0.02667 1.524 90)
			(unlocked yes)
			(layer "F.SilkS")
			(effects
				(font
					(size 0.7874 0.5842)
					(thickness 0.127)
				)
				(justify left)
			)
		)
		(property "Value" "4.75K"
			(at -0.148158 1.3462 270)
			(unlocked yes)
			(layer "F.Fab")
			(hide yes)
			(effects
				(font
					(size 1.27 0.9652)
					(thickness 0.000001)
				)
				(justify left)
			)
		)
		(property "Device Type" "REST4024"
			(at -0.148158 1.3462 270)
			(unlocked yes)
			(layer "F.Fab")
			(hide yes)
			(effects
				(font
					(size 1.27 0.9652)
					(thickness 0.000001)
				)
				(justify left)
			)
		)
		(duplicate_pad_numbers_are_jumpers no)
		(fp_poly
			(pts
				(xy 0.635 1.0668) (xy 0.635 -1.0668) (xy -0.635 -1.0668) (xy -0.635 1.0668)
			)
			(stroke
				(width 0)
				(type default)
			)
			(fill no)
			(layer "F.CrtYd")
		)
		(fp_line
			(start 0.254 0.508)
			(end -0.254 0.508)
			(stroke
				(width 0.0254)
				(type default)
			)
			(layer "F.Fab")
		)
		(fp_line
			(start 0.254 -0.508)
			(end 0.254 0.508)
			(stroke
				(width 0.0254)
				(type default)
			)
			(layer "F.Fab")
		)
		(fp_line
			(start -0.254 0.508)
			(end -0.254 -0.508)
			(stroke
				(width 0.0254)
				(type default)
			)
			(layer "F.Fab")
		)
		(fp_line
			(start -0.254 -0.508)
			(end 0.254 -0.508)
			(stroke
				(width 0.0254)
				(type default)
			)
			(layer "F.Fab")
		)
		(pad "1" smd rect
			(at 0 -0.4191 180)
			(size 0.508 0.5334)
			(layers "F.Cu" "F.Mask" "F.Paste")
			(net "_NFP_CORE_VID0")
		)
		(pad "2" smd rect
			(at 0 0.4191 180)
			(size 0.508 0.5334)
			(layers "F.Cu" "F.Mask" "F.Paste")
			(net "VDD_1.2V")
		)
		(zone
			(layer "F.Cu")
			(hatch none 0.5)
			(connect_pads
				(clearance 0)
			)
			(min_thickness 0.25)
			(keepout
				(tracks not_allowed)
				(vias allowed)
				(pads allowed)
				(copperpour not_allowed)
				(footprints allowed)
			)
			(placement
				(enabled no)
				(sheetname "")
			)
			(fill
				(thermal_gap 0.5)
				(thermal_bridge_width 0.5)
				(island_removal_mode 0)
			)
			(polygon
				(pts
					(xy 26.5176 32.6644) (xy 26.5176 32.6136) (xy 26.5684 32.6136) (xy 26.5684 32.6644)
				)
			)
		)
	)
	(footprint ""
		(layer "F.Cu")
		(at 36.322 38.989 90)
		(property "Reference" "R314"
			(at 0 0 90)
			(layer "F.SilkS")
			(hide yes)
			(effects
				(font
					(size 1.27 1.27)
				)
			)
		)
		(property "Value" "1.0K"
			(at -0.148158 1.3462 180)
			(unlocked yes)
			(layer "F.Fab")
			(hide yes)
			(effects
				(font
					(size 1.27 0.9652)
					(thickness 0.000001)
				)
				(justify left)
			)
		)
		(property "Device Type" "REST0025"
			(at -0.148158 1.3462 180)
			(unlocked yes)
			(layer "F.Fab")
			(hide yes)
			(effects
				(font
					(size 1.27 0.9652)
					(thickness 0.000001)
				)
				(justify left)
			)
		)
		(duplicate_pad_numbers_are_jumpers no)
		(fp_poly
			(pts
				(xy 0.635 1.0668) (xy 0.635 -1.0668) (xy -0.635 -1.0668) (xy -0.635 1.0668)
			)
			(stroke
				(width 0)
				(type default)
			)
			(fill no)
			(layer "F.CrtYd")
		)
		(fp_line
			(start 0.254 -0.508)
			(end 0.254 0.508)
			(stroke
				(width 0.0254)
				(type default)
			)
			(layer "F.Fab")
		)
		(fp_line
			(start -0.254 -0.508)
			(end 0.254 -0.508)
			(stroke
				(width 0.0254)
				(type default)
			)
			(layer "F.Fab")
		)
		(fp_line
			(start 0.254 0.508)
			(end -0.254 0.508)
			(stroke
				(width 0.0254)
				(type default)
			)
			(layer "F.Fab")
		)
		(fp_line
			(start -0.254 0.508)
			(end -0.254 -0.508)
			(stroke
				(width 0.0254)
				(type default)
			)
			(layer "F.Fab")
		)
		(pad "1" smd rect
			(at 0 -0.4191 90)
			(size 0.508 0.5334)
			(layers "F.Cu" "F.Mask" "F.Paste")
			(net "_SW1")
		)
		(pad "2" smd rect
			(at 0 0.4191 90)
			(size 0.508 0.5334)
			(layers "F.Cu" "F.Mask" "F.Paste")
			(net "NFP_VDD_CORE_ISEN1_P")
		)
		(zone
			(layer "F.Cu")
			(hatch none 0.5)
			(connect_pads
				(clearance 0)
			)
			(min_thickness 0.25)
			(keepout
				(tracks not_allowed)
				(vias allowed)
				(pads allowed)
				(copperpour not_allowed)
				(footprints allowed)
			)
			(placement
				(enabled no)
				(sheetname "")
			)
			(fill
				(thermal_gap 0.5)
				(thermal_bridge_width 0.5)
				(island_removal_mode 0)
			)
			(polygon
				(pts
					(xy 36.2966 38.9636) (xy 36.3474 38.9636) (xy 36.3474 39.0144) (xy 36.2966 39.0144)
				)
			)
		)
	)
	(footprint ""
		(layer "F.Cu")
		(at 77.343 43.688)
		(property "Reference" "C139"
			(at 0.28067 -1.397 90)
			(unlocked yes)
			(layer "F.SilkS")
			(effects
				(font
					(size 0.7874 0.5842)
					(thickness 0.127)
				)
				(justify left)
			)
		)
		(property "Value" "10UF"
			(at -0.148158 1.7526 90)
			(unlocked yes)
			(layer "F.Fab")
			(hide yes)
			(effects
				(font
					(size 1.27 0.9652)
					(thickness 0.000001)
				)
				(justify left)
			)
		)
		(property "Device Type" "CAPC0058"
			(at -0.148158 1.7526 90)
			(unlocked yes)
			(layer "F.Fab")
			(hide yes)
			(effects
				(font
					(size 1.27 0.9652)
					(thickness 0.000001)
				)
				(justify left)
			)
		)
		(duplicate_pad_numbers_are_jumpers no)
		(fp_circle
			(center 0 0)
			(end 0.127 0)
			(stroke
				(width 0.2032)
				(type default)
			)
			(fill no)
			(layer "F.SilkS")
		)
		(fp_poly
			(pts
				(xy 0.7874 -1.6637) (xy -0.7874 -1.6637) (xy -0.7874 1.6637) (xy 0.7874 1.6637)
			)
			(stroke
				(width 0)
				(type default)
			)
			(fill no)
			(layer "F.CrtYd")
		)
		(fp_line
			(start -0.4064 -0.7874)
			(end 0.4064 -0.7874)
			(stroke
				(width 0.0254)
				(type default)
			)
			(layer "F.Fab")
		)
		(fp_line
			(start -0.4064 0.8128)
			(end -0.4064 -0.7874)
			(stroke
				(width 0.0254)
				(type default)
			)
			(layer "F.Fab")
		)
		(fp_line
			(start 0.4064 -0.7874)
			(end 0.4064 0.8128)
			(stroke
				(width 0.0254)
				(type default)
			)
			(layer "F.Fab")
		)
		(fp_line
			(start 0.4064 0.8128)
			(end -0.4064 0.8128)
			(stroke
				(width 0.0254)
				(type default)
			)
			(layer "F.Fab")
		)
		(pad "1" smd rect
			(at 0 -0.8001)
			(size 0.8636 0.9652)
			(layers "F.Cu" "F.Mask" "F.Paste")
			(net "DDR_VTT")
		)
		(pad "2" smd rect
			(at 0 0.8001)
			(size 0.8636 0.9652)
			(layers "F.Cu" "F.Mask" "F.Paste")
			(net "GND")
		)
	)
	(footprint ""
		(layer "F.Cu")
		(at 2.413 34.163 180)
		(property "Reference" "R131"
			(at 0 0 180)
			(layer "F.SilkS")
			(hide yes)
			(effects
				(font
					(size 1.27 1.27)
				)
			)
		)
		(property "Value" "2K"
			(at -0.148158 1.3462 270)
			(unlocked yes)
			(layer "F.Fab")
			(hide yes)
			(effects
				(font
					(size 1.27 0.9652)
					(thickness 0.000001)
				)
				(justify left)
			)
		)
		(property "Device Type" "REST0138"
			(at -0.148158 1.3462 270)
			(unlocked yes)
			(layer "F.Fab")
			(hide yes)
			(effects
				(font
					(size 1.27 0.9652)
					(thickness 0.000001)
				)
				(justify left)
			)
		)
		(duplicate_pad_numbers_are_jumpers no)
		(fp_poly
			(pts
				(xy 0.635 1.0668) (xy 0.635 -1.0668) (xy -0.635 -1.0668) (xy -0.635 1.0668)
			)
			(stroke
				(width 0)
				(type default)
			)
			(fill no)
			(layer "F.CrtYd")
		)
		(fp_line
			(start 0.254 0.508)
			(end -0.254 0.508)
			(stroke
				(width 0.0254)
				(type default)
			)
			(layer "F.Fab")
		)
		(fp_line
			(start 0.254 -0.508)
			(end 0.254 0.508)
			(stroke
				(width 0.0254)
				(type default)
			)
			(layer "F.Fab")
		)
		(fp_line
			(start -0.254 0.508)
			(end -0.254 -0.508)
			(stroke
				(width 0.0254)
				(type default)
			)
			(layer "F.Fab")
		)
		(fp_line
			(start -0.254 -0.508)
			(end 0.254 -0.508)
			(stroke
				(width 0.0254)
				(type default)
			)
			(layer "F.Fab")
		)
		(pad "1" smd rect
			(at 0 -0.4191 180)
			(size 0.508 0.5334)
			(layers "F.Cu" "F.Mask" "F.Paste")
			(net "PSU_I2C_SCL")
		)
		(pad "2" smd rect
			(at 0 0.4191 180)
			(size 0.508 0.5334)
			(layers "F.Cu" "F.Mask" "F.Paste")
			(net "EXT_3.3V")
		)
		(zone
			(layer "F.Cu")
			(hatch none 0.5)
			(connect_pads
				(clearance 0)
			)
			(min_thickness 0.25)
			(keepout
				(tracks not_allowed)
				(vias allowed)
				(pads allowed)
				(copperpour not_allowed)
				(footprints allowed)
			)
			(placement
				(enabled no)
				(sheetname "")
			)
			(fill
				(thermal_gap 0.5)
				(thermal_bridge_width 0.5)
				(island_removal_mode 0)
			)
			(polygon
				(pts
					(xy 2.3876 34.1884) (xy 2.3876 34.1376) (xy 2.4384 34.1376) (xy 2.4384 34.1884)
				)
			)
		)
	)
	(footprint ""
		(layer "F.Cu")
		(at 80.645 11.811 -90)
		(property "Reference" "C216"
			(at 0.91567 1.778 0)
			(unlocked yes)
			(layer "F.SilkS")
			(effects
				(font
					(size 0.7874 0.5842)
					(thickness 0.127)
				)
				(justify left)
			)
		)
		(property "Value" "1UF"
			(at -0.091846 0.2921 0)
			(unlocked yes)
			(layer "F.Fab")
			(hide yes)
			(effects
				(font
					(size 0.7874 0.5842)
					(thickness 0.2032)
				)
				(justify left)
			)
		)
		(property "Device Type" "CAPC0028"
			(at -0.091846 0.2921 0)
			(unlocked yes)
			(layer "F.Fab")
			(hide yes)
			(effects
				(font
					(size 0.7874 0.5842)
					(thickness 0.2032)
				)
				(justify left)
			)
		)
		(duplicate_pad_numbers_are_jumpers no)
		(fp_poly
			(pts
				(xy 0.635 1.0668) (xy 0.635 -1.0668) (xy -0.635 -1.0668) (xy -0.635 1.0668)
			)
			(stroke
				(width 0)
				(type default)
			)
			(fill no)
			(layer "F.CrtYd")
		)
		(fp_line
			(start -0.254 0.508)
			(end -0.254 -0.508)
			(stroke
				(width 0.0254)
				(type default)
			)
			(layer "F.Fab")
		)
		(fp_line
			(start 0.254 0.508)
			(end -0.254 0.508)
			(stroke
				(width 0.0254)
				(type default)
			)
			(layer "F.Fab")
		)
		(fp_line
			(start -0.254 -0.508)
			(end 0.254 -0.508)
			(stroke
				(width 0.0254)
				(type default)
			)
			(layer "F.Fab")
		)
		(fp_line
			(start 0.254 -0.508)
			(end 0.254 0.508)
			(stroke
				(width 0.0254)
				(type default)
			)
			(layer "F.Fab")
		)
		(pad "1" smd rect
			(at 0 -0.4191 270)
			(size 0.508 0.5334)
			(layers "F.Cu" "F.Mask" "F.Paste")
			(net "DDR_VDDQ")
		)
		(pad "2" smd rect
			(at 0 0.4191 270)
			(size 0.508 0.5334)
			(layers "F.Cu" "F.Mask" "F.Paste")
			(net "GND")
		)
		(zone
			(layer "F.Cu")
			(hatch none 0.5)
			(connect_pads
				(clearance 0)
			)
			(min_thickness 0.25)
			(keepout
				(tracks not_allowed)
				(vias allowed)
				(pads allowed)
				(copperpour not_allowed)
				(footprints allowed)
			)
			(placement
				(enabled no)
				(sheetname "")
			)
			(fill
				(thermal_gap 0.5)
				(thermal_bridge_width 0.5)
				(island_removal_mode 0)
			)
			(polygon
				(pts
					(xy 80.6704 11.8364) (xy 80.6196 11.8364) (xy 80.6196 11.7856) (xy 80.6704 11.7856)
				)
			)
		)
	)
	(footprint ""
		(layer "F.Cu")
		(at 26.162 8.509)
		(property "Reference" "R351"
			(at 0.91567 1.397 90)
			(unlocked yes)
			(layer "F.SilkS")
			(effects
				(font
					(size 0.7874 0.5842)
					(thickness 0.127)
				)
				(justify left)
			)
		)
		(property "Value" "0"
			(at -0.148158 1.3462 90)
			(unlocked yes)
			(layer "F.Fab")
			(hide yes)
			(effects
				(font
					(size 1.27 0.9652)
					(thickness 0.000001)
				)
				(justify left)
			)
		)
		(property "Device Type" "REST1111"
			(at -0.148158 1.3462 90)
			(unlocked yes)
			(layer "F.Fab")
			(hide yes)
			(effects
				(font
					(size 1.27 0.9652)
					(thickness 0.000001)
				)
				(justify left)
			)
		)
		(duplicate_pad_numbers_are_jumpers no)
		(fp_poly
			(pts
				(xy 0.635 1.0668) (xy 0.635 -1.0668) (xy -0.635 -1.0668) (xy -0.635 1.0668)
			)
			(stroke
				(width 0)
				(type default)
			)
			(fill no)
			(layer "F.CrtYd")
		)
		(fp_line
			(start -0.254 -0.508)
			(end 0.254 -0.508)
			(stroke
				(width 0.0254)
				(type default)
			)
			(layer "F.Fab")
		)
		(fp_line
			(start -0.254 0.508)
			(end -0.254 -0.508)
			(stroke
				(width 0.0254)
				(type default)
			)
			(layer "F.Fab")
		)
		(fp_line
			(start 0.254 -0.508)
			(end 0.254 0.508)
			(stroke
				(width 0.0254)
				(type default)
			)
			(layer "F.Fab")
		)
		(fp_line
			(start 0.254 0.508)
			(end -0.254 0.508)
			(stroke
				(width 0.0254)
				(type default)
			)
			(layer "F.Fab")
		)
		(pad "1" smd rect
			(at 0 -0.4191)
			(size 0.508 0.5334)
			(layers "F.Cu" "F.Mask" "F.Paste")
			(net "NFP_SMBUS_SDA")
		)
		(pad "2" smd rect
			(at 0 0.4191)
			(size 0.508 0.5334)
			(layers "F.Cu" "F.Mask" "F.Paste")
			(net "SMBUS_SDA")
		)
		(zone
			(layer "F.Cu")
			(hatch none 0.5)
			(connect_pads
				(clearance 0)
			)
			(min_thickness 0.25)
			(keepout
				(tracks not_allowed)
				(vias allowed)
				(pads allowed)
				(copperpour not_allowed)
				(footprints allowed)
			)
			(placement
				(enabled no)
				(sheetname "")
			)
			(fill
				(thermal_gap 0.5)
				(thermal_bridge_width 0.5)
				(island_removal_mode 0)
			)
			(polygon
				(pts
					(xy 26.1874 8.4836) (xy 26.1874 8.5344) (xy 26.1366 8.5344) (xy 26.1366 8.4836)
				)
			)
		)
	)
)
